# BASEBOARD_FAB2 (Tioga Pass) — schematic netlist excerpt (pin names and nets, part order shuffled) for the footprints in the layout excerpt that follows; sources: Cadence DE-HDL packaged netlist, KiCad conversion of Wiwynn_Tioga_Pass_MB.brd

T1D6  TEST-PAD-12P-1-GP-U  pkg DISCRET-GB1  page 257
  DP  = L5_85OHM_5INCH_DN
  DN  = L5_85OHM_5INCH_DP
  GND(0)  = GND
  GND(1)  = GND
  GND(2)  = GND
  GND(3)  = GND
  GND(4)  = GND
  GND(5)  = GND
  GND(6)  = GND
  GND(7)  = GND
  GND(8)  = GND
  GND(9)  = GND

R9P19  RES  10.0K 1% EMPTY  pkg 0402  page 200 : A = A_HSC_TIMER_R ; B = AGND_HSC

(kicad_pcb
	(version 20260206)
	(generator "pcbnew")
	(generator_version "10.0")
	(general
		(thickness 1.6)
		(legacy_teardrops no)
	)
	(paper "A4")
	(title_block
		(title "Wiwynn_Tioga_Pass_MB.brd")
		(comment 1 "Tioga Pass / footprints 4472-4473 of 4770")
	)
	(layers
		(0 "F.Cu" signal "TOP")
		(4 "In1.Cu" signal "L2GND")
		(6 "In2.Cu" signal "L3")
		(8 "In3.Cu" signal "L4GND")
		(10 "In4.Cu" signal "L5")
		(12 "In5.Cu" signal "L6GND")
		(14 "In6.Cu" signal "L7VCC")
		(16 "In7.Cu" signal "L8VCC")
		(18 "In8.Cu" signal "L9GND")
		(20 "In9.Cu" signal "L10")
		(22 "In10.Cu" signal "L11GND")
		(24 "In11.Cu" signal "L12")
		(26 "In12.Cu" signal "L13GND")
		(2 "B.Cu" signal "BOTTOM")
		(9 "F.Adhes" user "F.Adhesive")
		(11 "B.Adhes" user "B.Adhesive")
		(13 "F.Paste" user "Package Geometry/Pastemask Top")
		(15 "B.Paste" user "Package Geometry/Pastemask Bottom")
		(5 "F.SilkS" user "Ref Des/Silkscreen Top")
		(7 "B.SilkS" user "Ref Des/Silkscreen Bottom")
		(1 "F.Mask" user "Board Geometry/Soldermask Top")
		(3 "B.Mask" user "Board Geometry/Soldermask Bottom")
		(17 "Dwgs.User" user "User.Drawings")
		(19 "Cmts.User" user "User.Comments")
		(21 "Eco1.User" user "User.Eco1")
		(23 "Eco2.User" user "User.Eco2")
		(25 "Edge.Cuts" user "Board Geometry/Outline")
		(27 "Margin" user)
		(31 "F.CrtYd" user "Package Geometry/Place Bound Top")
		(29 "B.CrtYd" user "Package Geometry/Place Bound Bottom")
		(35 "F.Fab" user "Ref Des/Assembly Top")
		(33 "B.Fab" user "Ref Des/Assembly Bottom")
	)
	(footprint ""
		(layer "B.Cu")
		(at 149.065234 -164.916866 90)
		(property "Reference" "T1D6"
			(at 0 0 90)
			(layer "B.SilkS")
			(hide yes)
			(effects
				(font
					(size 1.27 1.27)
				)
				(justify mirror)
			)
		)
		(property "Value" "*"
			(at 3.4036 -4.46405 90)
			(unlocked yes)
			(layer "B.Fab")
			(hide yes)
			(effects
				(font
					(size 0.889 0.889)
					(thickness 0.1524)
				)
				(justify mirror)
			)
		)
		(property "Device Type" "TEST-PAD-12P-1-GP-U_DISCRET-GBA"
			(at 3.4036 -5.98805 90)
			(unlocked yes)
			(layer "B.Fab")
			(hide yes)
			(effects
				(font
					(size 0.889 0.889)
					(thickness 0.1524)
				)
				(justify mirror)
			)
		)
		(duplicate_pad_numbers_are_jumpers no)
		(fp_line
			(start 2.3876 -4.826)
			(end -2.3622 -4.826)
			(stroke
				(width 0.1524)
				(type default)
			)
			(layer "B.SilkS")
		)
		(fp_line
			(start -2.3622 -4.826)
			(end -2.3622 3.4798)
			(stroke
				(width 0.1524)
				(type default)
			)
			(layer "B.SilkS")
		)
		(fp_line
			(start 2.3876 3.4798)
			(end 2.3876 -4.826)
			(stroke
				(width 0.1524)
				(type default)
			)
			(layer "B.SilkS")
		)
		(fp_line
			(start -2.3622 3.4798)
			(end 2.3876 3.4798)
			(stroke
				(width 0.1524)
				(type default)
			)
			(layer "B.SilkS")
		)
		(fp_rect
			(start 2.6416 3.7338)
			(end -2.6162 -5.08)
			(stroke
				(width 0)
				(type default)
			)
			(fill no)
			(layer "B.CrtYd")
		)
		(fp_rect
			(start 2.6416 3.7338)
			(end -2.6162 -5.08)
			(stroke
				(width 0)
				(type default)
			)
			(fill no)
			(layer "B.Fab")
		)
		(pad "1" smd circle
			(at -0.496824 -1.301496 270)
			(size 0.6604 0.6604)
			(layers "B.Cu" "B.Mask" "B.Paste")
			(net "L5_85OHM_5INCH_DN")
		)
		(pad "2" smd circle
			(at 0.503936 -1.301496 270)
			(size 0.6604 0.6604)
			(layers "B.Cu" "B.Mask" "B.Paste")
			(net "L5_85OHM_5INCH_DP")
		)
		(pad "3" smd custom
			(at 0.00889 0.370078 270)
			(size 0.74295 0.74295)
			(layers "B.Cu" "B.Mask" "B.Paste")
			(net "GND")
			(options
				(clearance outline)
				(anchor circle)
			)
			(primitives
				(gr_poly
					(pts
						(xy -2.1209 -1.4859) (xy 2.1209 -1.4859) (xy 2.1209 1.4859) (xy 1.08585 1.4859) (xy 1.08585 0.4699)
						(xy -1.08585 0.4699) (xy -1.08585 1.4859) (xy -2.1209 1.4859)
					)
					(width 0)
					(fill yes)
				)
			)
		)
		(pad "4" thru_hole circle
			(at -1.266444 -3.851656 270)
			(size 1.4478 1.4478)
			(drill 1.0414)
			(layers "*.Cu" "*.Mask")
			(remove_unused_layers no)
			(net "GND")
			(clearance 0.1524)
			(thermal_gap 0.1524)
		)
		(pad "5" thru_hole circle
			(at 1.273556 -3.851656 270)
			(size 1.4478 1.4478)
			(drill 1.0414)
			(layers "*.Cu" "*.Mask")
			(remove_unused_layers no)
			(net "GND")
			(clearance 0.1524)
			(thermal_gap 0.1524)
		)
		(pad "6" thru_hole circle
			(at -1.266444 2.498344 270)
			(size 1.4478 1.4478)
			(drill 1.0414)
			(layers "*.Cu" "*.Mask")
			(remove_unused_layers no)
			(net "GND")
			(clearance 0.1524)
			(thermal_gap 0.1524)
		)
		(pad "7" thru_hole circle
			(at 1.273556 2.498344 270)
			(size 1.4478 1.4478)
			(drill 1.0414)
			(layers "*.Cu" "*.Mask")
			(remove_unused_layers no)
			(net "GND")
			(clearance 0.1524)
			(thermal_gap 0.1524)
		)
		(pad "8" thru_hole circle
			(at -1.27 -0.4572 270)
			(size 0.7112 0.7112)
			(drill 0.4064)
			(layers "*.Cu" "*.Mask")
			(remove_unused_layers no)
			(net "GND")
			(clearance 0.1016)
			(thermal_gap 0.1016)
		)
		(pad "9" thru_hole circle
			(at -1.27 0.762 270)
			(size 0.7112 0.7112)
			(drill 0.4064)
			(layers "*.Cu" "*.Mask")
			(remove_unused_layers no)
			(net "GND")
			(clearance 0.1016)
			(thermal_gap 0.1016)
		)
		(pad "10" thru_hole circle
			(at 0.0254 0.762 270)
			(size 0.7112 0.7112)
			(drill 0.4064)
			(layers "*.Cu" "*.Mask")
			(remove_unused_layers no)
			(net "GND")
			(clearance 0.1016)
			(thermal_gap 0.1016)
		)
		(pad "11" thru_hole circle
			(at 1.27 0.762 270)
			(size 0.7112 0.7112)
			(drill 0.4064)
			(layers "*.Cu" "*.Mask")
			(remove_unused_layers no)
			(net "GND")
			(clearance 0.1016)
			(thermal_gap 0.1016)
		)
		(pad "12" thru_hole circle
			(at 1.27 -0.4572 270)
			(size 0.7112 0.7112)
			(drill 0.4064)
			(layers "*.Cu" "*.Mask")
			(remove_unused_layers no)
			(net "GND")
			(clearance 0.1016)
			(thermal_gap 0.1016)
		)
	)
	(footprint ""
		(layer "B.Cu")
		(at 24.765 -77.978)
		(property "Reference" "R9P19"
			(at 0 0 0)
			(layer "B.SilkS")
			(hide yes)
			(effects
				(font
					(size 1.27 1.27)
				)
				(justify mirror)
			)
		)
		(property "Value" ""
			(at 0 0 0)
			(layer "B.Fab")
			(effects
				(font
					(size 1.27 1.27)
				)
				(justify mirror)
			)
		)
		(duplicate_pad_numbers_are_jumpers no)
		(fp_poly
			(pts
				(xy 0.2794 -0.1016) (xy -0.2794 -0.1016) (xy -0.2794 0.9906) (xy 0.2794 0.9906)
			)
			(stroke
				(width 0)
				(type default)
			)
			(fill no)
			(layer "B.CrtYd")
		)
		(fp_line
			(start -0.2794 -0.1016)
			(end 0.2794 -0.1016)
			(stroke
				(width 0.1)
				(type default)
			)
			(layer "B.Fab")
		)
		(fp_line
			(start -0.2794 0.9906)
			(end -0.2794 -0.1016)
			(stroke
				(width 0.1)
				(type default)
			)
			(layer "B.Fab")
		)
		(fp_line
			(start 0.2794 -0.1016)
			(end 0.2794 0.9906)
			(stroke
				(width 0.1)
				(type default)
			)
			(layer "B.Fab")
		)
		(fp_line
			(start 0.2794 0.9906)
			(end -0.2794 0.9906)
			(stroke
				(width 0.1)
				(type default)
			)
			(layer "B.Fab")
		)
		(pad "1" smd rect
			(at 0 0 180)
			(size 0.508 0.508)
			(layers "B.Cu" "B.Mask" "B.Paste")
			(net "A_HSC_TIMER_R")
		)
		(pad "2" smd rect
			(at 0 0.889 180)
			(size 0.508 0.508)
			(layers "B.Cu" "B.Mask" "B.Paste")
			(net "AGND_HSC")
		)
		(zone
			(layer "B.Cu")
			(hatch none 0.5)
			(connect_pads
				(clearance 0)
			)
			(min_thickness 0.25)
			(keepout
				(tracks allowed)
				(vias not_allowed)
				(pads allowed)
				(copperpour not_allowed)
				(footprints allowed)
			)
			(placement
				(enabled no)
				(sheetname "")
			)
			(fill
				(thermal_gap 0.5)
				(thermal_bridge_width 0.5)
				(island_removal_mode 0)
			)
			(polygon
				(pts
					(xy 25.019 -77.724) (xy 24.511 -77.724) (xy 24.511 -77.343) (xy 25.019 -77.343)
				)
			)
		)
		(zone
			(layer "B.Cu")
			(hatch none 0.5)
			(connect_pads
				(clearance 0)
			)
			(min_thickness 0.25)
			(keepout
				(tracks not_allowed)
				(vias allowed)
				(pads allowed)
				(copperpour not_allowed)
				(footprints allowed)
			)
			(placement
				(enabled no)
				(sheetname "")
			)
			(fill
				(thermal_gap 0.5)
				(thermal_bridge_width 0.5)
				(island_removal_mode 0)
			)
			(polygon
				(pts
					(xy 25.019 -77.343) (xy 24.511 -77.343) (xy 24.511 -77.724) (xy 25.019 -77.724)
				)
			)
		)
	)
)
